# SCM (Grand Teton) — schematic netlist excerpt (pin names and nets, part order shuffled) for the footprints in the layout excerpt that follows; sources: Cadence DE-HDL packaged netlist, KiCad conversion of 12092022_DA0F0TMDCD0_F0T_Management_Board_D_brd_V3_OCP.brd

C202  Q_CAP  0.1UF 25V 10% X7R  pkg 0402  page 23 : A = P5V_AUX ; B = GND
C204  Q_CAP  1UF 16V 10% EMPTY  pkg 0603  page 23 : A = CRT_VCC5 ; B = GND

(kicad_pcb
	(version 20260206)
	(generator "pcbnew")
	(generator_version "10.0")
	(general
		(thickness 1.6)
		(legacy_teardrops no)
	)
	(paper "A4")
	(title_block
		(title "12092022_DA0F0TMDCD0_F0T_Management_Board_D_brd_V3_OCP.brd")
		(comment 1 "Grand Teton / footprints 773-774 of 1440")
	)
	(layers
		(0 "F.Cu" signal "TOP")
		(4 "In1.Cu" signal "GND")
		(6 "In2.Cu" signal "IN1")
		(8 "In3.Cu" signal "GND1")
		(10 "In4.Cu" signal "IN2")
		(12 "In5.Cu" signal "VCC")
		(14 "In6.Cu" signal "VCC1")
		(16 "In7.Cu" signal "IN3")
		(18 "In8.Cu" signal "GND2")
		(20 "In9.Cu" signal "IN4")
		(22 "In10.Cu" signal "GND3")
		(2 "B.Cu" signal "BOTTOM")
		(9 "F.Adhes" user "F.Adhesive")
		(11 "B.Adhes" user "B.Adhesive")
		(13 "F.Paste" user "Package Geometry/Pastemask Top")
		(15 "B.Paste" user "Package Geometry/Pastemask Bottom")
		(5 "F.SilkS" user "Ref Des/Silkscreen Top")
		(7 "B.SilkS" user "Ref Des/Silkscreen Bottom")
		(1 "F.Mask" user "Board Geometry/Soldermask Top")
		(3 "B.Mask" user "Board Geometry/Soldermask Bottom")
		(17 "Dwgs.User" user "User.Drawings")
		(19 "Cmts.User" user "User.Comments")
		(21 "Eco1.User" user "User.Eco1")
		(23 "Eco2.User" user "User.Eco2")
		(25 "Edge.Cuts" user "Board Geometry/Outline")
		(27 "Margin" user)
		(31 "F.CrtYd" user "Package Geometry/Place Bound Top")
		(29 "B.CrtYd" user "Package Geometry/Place Bound Bottom")
		(35 "F.Fab" user "Ref Des/Assembly Top")
		(33 "B.Fab" user "Ref Des/Assembly Bottom")
	)
	(footprint ""
		(layer "B.Cu")
		(at 30.5435 -41.4147 -90)
		(property "Reference" "C202"
			(at 0 0 90)
			(layer "B.SilkS")
			(hide yes)
			(effects
				(font
					(size 1.27 1.27)
				)
				(justify mirror)
			)
		)
		(property "Value" ""
			(at 0 0 90)
			(layer "B.Fab")
			(effects
				(font
					(size 1.27 1.27)
				)
				(justify mirror)
			)
		)
		(duplicate_pad_numbers_are_jumpers no)
		(fp_line
			(start -0.7874 0.4064)
			(end 0.7874 0.4064)
			(stroke
				(width 0.1524)
				(type default)
			)
			(layer "B.SilkS")
		)
		(fp_line
			(start 0.7874 0.4064)
			(end 0.7874 -0.4064)
			(stroke
				(width 0.1524)
				(type default)
			)
			(layer "B.SilkS")
		)
		(fp_line
			(start -0.7874 -0.4064)
			(end -0.7874 0.4064)
			(stroke
				(width 0.1524)
				(type default)
			)
			(layer "B.SilkS")
		)
		(fp_line
			(start 0.7874 -0.4064)
			(end -0.7874 -0.4064)
			(stroke
				(width 0.1524)
				(type default)
			)
			(layer "B.SilkS")
		)
		(fp_line
			(start -0.67945 0.3048)
			(end -0.120396 0.3048)
			(stroke
				(width 0.1)
				(type default)
			)
			(layer "B.Fab")
		)
		(fp_line
			(start -0.120396 0.3048)
			(end -0.120396 0.2794)
			(stroke
				(width 0.1)
				(type default)
			)
			(layer "B.Fab")
		)
		(fp_line
			(start 0.12065 0.3048)
			(end 0.67945 0.3048)
			(stroke
				(width 0.1)
				(type default)
			)
			(layer "B.Fab")
		)
		(fp_line
			(start 0.67945 0.3048)
			(end 0.67945 -0.305054)
			(stroke
				(width 0.1)
				(type default)
			)
			(layer "B.Fab")
		)
		(fp_line
			(start -0.120396 0.2794)
			(end 0.12065 0.2794)
			(stroke
				(width 0.1)
				(type default)
			)
			(layer "B.Fab")
		)
		(fp_line
			(start 0.12065 0.2794)
			(end 0.12065 0.3048)
			(stroke
				(width 0.1)
				(type default)
			)
			(layer "B.Fab")
		)
		(fp_line
			(start -0.12065 -0.2794)
			(end -0.12065 -0.3048)
			(stroke
				(width 0.1)
				(type default)
			)
			(layer "B.Fab")
		)
		(fp_line
			(start 0.12065 -0.2794)
			(end -0.12065 -0.2794)
			(stroke
				(width 0.1)
				(type default)
			)
			(layer "B.Fab")
		)
		(fp_line
			(start -0.67945 -0.3048)
			(end -0.67945 0.3048)
			(stroke
				(width 0.1)
				(type default)
			)
			(layer "B.Fab")
		)
		(fp_line
			(start -0.12065 -0.3048)
			(end -0.67945 -0.3048)
			(stroke
				(width 0.1)
				(type default)
			)
			(layer "B.Fab")
		)
		(fp_line
			(start 0.12065 -0.305054)
			(end 0.12065 -0.2794)
			(stroke
				(width 0.1)
				(type default)
			)
			(layer "B.Fab")
		)
		(fp_line
			(start 0.67945 -0.305054)
			(end 0.12065 -0.305054)
			(stroke
				(width 0.1)
				(type default)
			)
			(layer "B.Fab")
		)
		(pad "1" smd circle
			(at 0.40005 0 90)
			(size 0 0)
			(layers "B.Cu" "B.Mask" "B.Paste")
			(net "P5V_AUX")
		)
		(pad "2" smd circle
			(at -0.40005 0 90)
			(size 0 0)
			(layers "B.Cu" "B.Mask" "B.Paste")
			(net "GND")
		)
	)
	(footprint ""
		(layer "B.Cu")
		(at 33.001712 -36.076128 90)
		(property "Reference" "C204"
			(at 0 0 90)
			(layer "B.SilkS")
			(hide yes)
			(effects
				(font
					(size 1.27 1.27)
				)
				(justify mirror)
			)
		)
		(property "Value" ""
			(at 0 0 90)
			(layer "B.Fab")
			(effects
				(font
					(size 1.27 1.27)
				)
				(justify mirror)
			)
		)
		(duplicate_pad_numbers_are_jumpers no)
		(fp_line
			(start 1.2954 -0.5842)
			(end -1.2954 -0.5842)
			(stroke
				(width 0.1524)
				(type default)
			)
			(layer "B.SilkS")
		)
		(fp_line
			(start 0 -0.5842)
			(end 0 0.5842)
			(stroke
				(width 0.1524)
				(type default)
			)
			(layer "B.SilkS")
		)
		(fp_line
			(start -1.2954 -0.5842)
			(end -1.2954 0.5842)
			(stroke
				(width 0.1524)
				(type default)
			)
			(layer "B.SilkS")
		)
		(fp_line
			(start 1.2954 0.5842)
			(end 1.2954 -0.5842)
			(stroke
				(width 0.1524)
				(type default)
			)
			(layer "B.SilkS")
		)
		(fp_line
			(start -1.2954 0.5842)
			(end 1.2954 0.5842)
			(stroke
				(width 0.1524)
				(type default)
			)
			(layer "B.SilkS")
		)
		(fp_line
			(start 0.8636 -0.4572)
			(end -0.8636 -0.4572)
			(stroke
				(width 0.1)
				(type default)
			)
			(layer "B.Fab")
		)
		(fp_line
			(start -0.8636 -0.4572)
			(end -0.8636 -0.4064)
			(stroke
				(width 0.1)
				(type default)
			)
			(layer "B.Fab")
		)
		(fp_line
			(start 1.1938 -0.4064)
			(end 0.8636 -0.4064)
			(stroke
				(width 0.1)
				(type default)
			)
			(layer "B.Fab")
		)
		(fp_line
			(start 0.8636 -0.4064)
			(end 0.8636 -0.4572)
			(stroke
				(width 0.1)
				(type default)
			)
			(layer "B.Fab")
		)
		(fp_line
			(start -0.8636 -0.4064)
			(end -1.1938 -0.4064)
			(stroke
				(width 0.1)
				(type default)
			)
			(layer "B.Fab")
		)
		(fp_line
			(start -1.1938 -0.4064)
			(end -1.1938 0.4064)
			(stroke
				(width 0.1)
				(type default)
			)
			(layer "B.Fab")
		)
		(fp_line
			(start 1.1938 0.4064)
			(end 1.1938 -0.4064)
			(stroke
				(width 0.1)
				(type default)
			)
			(layer "B.Fab")
		)
		(fp_line
			(start 0.8636 0.4064)
			(end 1.1938 0.4064)
			(stroke
				(width 0.1)
				(type default)
			)
			(layer "B.Fab")
		)
		(fp_line
			(start -0.8636 0.4064)
			(end -0.8636 0.4572)
			(stroke
				(width 0.1)
				(type default)
			)
			(layer "B.Fab")
		)
		(fp_line
			(start -1.1938 0.4064)
			(end -0.8636 0.4064)
			(stroke
				(width 0.1)
				(type default)
			)
			(layer "B.Fab")
		)
		(fp_line
			(start 0.8636 0.4572)
			(end 0.8636 0.4064)
			(stroke
				(width 0.1)
				(type default)
			)
			(layer "B.Fab")
		)
		(fp_line
			(start -0.8636 0.4572)
			(end 0.8636 0.4572)
			(stroke
				(width 0.1)
				(type default)
			)
			(layer "B.Fab")
		)
		(pad "1" smd rect
			(at 0.7366 0)
			(size 0.7112 0.8128)
			(layers "B.Cu" "B.Mask" "B.Paste")
			(net "CRT_VCC5")
		)
		(pad "2" smd rect
			(at -0.7366 0)
			(size 0.7112 0.8128)
			(layers "B.Cu" "B.Mask" "B.Paste")
			(net "GND")
		)
	)
)
